# BASEBOARD_FAB2 (Tioga Pass) — schematic netlist excerpt (pin names and nets, part order shuffled) for the footprints in the layout excerpt that follows; sources: Cadence DE-HDL packaged netlist, KiCad conversion of Wiwynn_Tioga_Pass_MB.brd

R3W6  RES  4.75K 1% CHIP  pkg 0402  page 249 : A = P3V3_STBY ; B = RST_BMC_EXTRST_N

U3P2  GTL2014  IC  pkg SM  page 92
  DIR  = PD_GTL2104_DIR_1
  B0  = PWRGD_CPUPWRGD_GTL
  B1  = H_CPU1_FIVR_FAULT_G
  VREF  = P0V7_GTL2104_VREF_1
  B2  = H_CPU_CATERR_G_N
  B3  = H_CPU1_THERMTRIP_G_N
  GND(0)  = GND
  GND(1)  = GND
  A3  = FM_CPU1_THERMTRIP_LVT3_R_N
  A2  = FM_CPU_CATERR_LVT3_R2_N
  GND(2)  = GND
  A1  = FM_CPU1_FIVR_FAULT_R_LVT3
  A0  = PWRGD_CPUPWRGD_R1
  VCC  = P3V3

(kicad_pcb
	(version 20260206)
	(generator "pcbnew")
	(generator_version "10.0")
	(general
		(thickness 1.6)
		(legacy_teardrops no)
	)
	(paper "A4")
	(title_block
		(title "Wiwynn_Tioga_Pass_MB.brd")
		(comment 1 "Tioga Pass / footprints 3556-3557 of 4770")
	)
	(layers
		(0 "F.Cu" signal "TOP")
		(4 "In1.Cu" signal "L2GND")
		(6 "In2.Cu" signal "L3")
		(8 "In3.Cu" signal "L4GND")
		(10 "In4.Cu" signal "L5")
		(12 "In5.Cu" signal "L6GND")
		(14 "In6.Cu" signal "L7VCC")
		(16 "In7.Cu" signal "L8VCC")
		(18 "In8.Cu" signal "L9GND")
		(20 "In9.Cu" signal "L10")
		(22 "In10.Cu" signal "L11GND")
		(24 "In11.Cu" signal "L12")
		(26 "In12.Cu" signal "L13GND")
		(2 "B.Cu" signal "BOTTOM")
		(9 "F.Adhes" user "F.Adhesive")
		(11 "B.Adhes" user "B.Adhesive")
		(13 "F.Paste" user "Package Geometry/Pastemask Top")
		(15 "B.Paste" user "Package Geometry/Pastemask Bottom")
		(5 "F.SilkS" user "Ref Des/Silkscreen Top")
		(7 "B.SilkS" user "Ref Des/Silkscreen Bottom")
		(1 "F.Mask" user "Board Geometry/Soldermask Top")
		(3 "B.Mask" user "Board Geometry/Soldermask Bottom")
		(17 "Dwgs.User" user "User.Drawings")
		(19 "Cmts.User" user "User.Comments")
		(21 "Eco1.User" user "User.Eco1")
		(23 "Eco2.User" user "User.Eco2")
		(25 "Edge.Cuts" user "Board Geometry/Outline")
		(27 "Margin" user)
		(31 "F.CrtYd" user "Package Geometry/Place Bound Top")
		(29 "B.CrtYd" user "Package Geometry/Place Bound Bottom")
		(35 "F.Fab" user "Ref Des/Assembly Top")
		(33 "B.Fab" user "Ref Des/Assembly Bottom")
	)
	(footprint ""
		(layer "B.Cu")
		(at 438.703974 -22.6314 -90)
		(property "Reference" "R3W6"
			(at 0.8382 -0.67818 270)
			(unlocked yes)
			(layer "B.SilkS")
			(effects
				(font
					(size 0.4064 0.254)
					(thickness 0.1524)
				)
				(justify left mirror)
			)
		)
		(property "Value" ""
			(at 0 0 90)
			(layer "B.Fab")
			(effects
				(font
					(size 1.27 1.27)
				)
				(justify mirror)
			)
		)
		(duplicate_pad_numbers_are_jumpers no)
		(fp_poly
			(pts
				(xy 0.2794 -0.1016) (xy -0.2794 -0.1016) (xy -0.2794 0.9906) (xy 0.2794 0.9906)
			)
			(stroke
				(width 0)
				(type default)
			)
			(fill no)
			(layer "B.CrtYd")
		)
		(fp_line
			(start -0.2794 0.9906)
			(end -0.2794 -0.1016)
			(stroke
				(width 0.1)
				(type default)
			)
			(layer "B.Fab")
		)
		(fp_line
			(start 0.2794 0.9906)
			(end -0.2794 0.9906)
			(stroke
				(width 0.1)
				(type default)
			)
			(layer "B.Fab")
		)
		(fp_line
			(start -0.2794 -0.1016)
			(end 0.2794 -0.1016)
			(stroke
				(width 0.1)
				(type default)
			)
			(layer "B.Fab")
		)
		(fp_line
			(start 0.2794 -0.1016)
			(end 0.2794 0.9906)
			(stroke
				(width 0.1)
				(type default)
			)
			(layer "B.Fab")
		)
		(pad "1" smd rect
			(at 0 0 90)
			(size 0.508 0.508)
			(layers "B.Cu" "B.Mask" "B.Paste")
			(net "P3V3_STBY")
		)
		(pad "2" smd rect
			(at 0 0.889 90)
			(size 0.508 0.508)
			(layers "B.Cu" "B.Mask" "B.Paste")
			(net "RST_BMC_EXTRST_N")
		)
		(zone
			(layer "B.Cu")
			(hatch none 0.5)
			(connect_pads
				(clearance 0)
			)
			(min_thickness 0.25)
			(keepout
				(tracks not_allowed)
				(vias allowed)
				(pads allowed)
				(copperpour not_allowed)
				(footprints allowed)
			)
			(placement
				(enabled no)
				(sheetname "")
			)
			(fill
				(thermal_gap 0.5)
				(thermal_bridge_width 0.5)
				(island_removal_mode 0)
			)
			(polygon
				(pts
					(xy 438.068974 -22.3774) (xy 438.068974 -22.8854) (xy 438.449974 -22.8854) (xy 438.449974 -22.3774)
				)
			)
		)
		(zone
			(layer "B.Cu")
			(hatch none 0.5)
			(connect_pads
				(clearance 0)
			)
			(min_thickness 0.25)
			(keepout
				(tracks allowed)
				(vias not_allowed)
				(pads allowed)
				(copperpour not_allowed)
				(footprints allowed)
			)
			(placement
				(enabled no)
				(sheetname "")
			)
			(fill
				(thermal_gap 0.5)
				(thermal_bridge_width 0.5)
				(island_removal_mode 0)
			)
			(polygon
				(pts
					(xy 438.449974 -22.3774) (xy 438.449974 -22.8854) (xy 438.068974 -22.8854) (xy 438.068974 -22.3774)
				)
			)
		)
	)
	(footprint ""
		(layer "B.Cu")
		(at 370.3955 -60.87872)
		(property "Reference" "U3P2"
			(at -4.435856 5.186172 180)
			(unlocked yes)
			(layer "B.SilkS")
			(effects
				(font
					(size 0.7874 0.5842)
					(thickness 0.1524)
				)
				(justify left mirror)
			)
		)
		(property "Value" ""
			(at 0 0 0)
			(layer "B.Fab")
			(effects
				(font
					(size 1.27 1.27)
				)
				(justify mirror)
			)
		)
		(duplicate_pad_numbers_are_jumpers no)
		(fp_line
			(start -4.4323 -0.64008)
			(end -4.4323 4.52628)
			(stroke
				(width 0.1524)
				(type default)
			)
			(layer "B.SilkS")
		)
		(fp_line
			(start -4.4323 4.52628)
			(end -1.5367 4.52628)
			(stroke
				(width 0.1524)
				(type default)
			)
			(layer "B.SilkS")
		)
		(fp_line
			(start -3.302 0.49022)
			(end -3.302 -0.64008)
			(stroke
				(width 0.1524)
				(type default)
			)
			(layer "B.SilkS")
		)
		(fp_line
			(start -2.667 -0.64008)
			(end -2.667 0.49022)
			(stroke
				(width 0.1524)
				(type default)
			)
			(layer "B.SilkS")
		)
		(fp_line
			(start -2.667 0.49022)
			(end -3.302 0.49022)
			(stroke
				(width 0.1524)
				(type default)
			)
			(layer "B.SilkS")
		)
		(fp_line
			(start -1.5367 -0.64008)
			(end -4.4323 -0.64008)
			(stroke
				(width 0.1524)
				(type default)
			)
			(layer "B.SilkS")
		)
		(fp_line
			(start -1.5367 4.52628)
			(end -1.5367 -0.64008)
			(stroke
				(width 0.1524)
				(type default)
			)
			(layer "B.SilkS")
		)
		(fp_circle
			(center 1.612138 -0.684784)
			(end 1.739138 -0.684784)
			(stroke
				(width 0.254)
				(type default)
			)
			(fill no)
			(layer "B.SilkS")
		)
		(fp_poly
			(pts
				(xy -0.7366 4.54152) (xy -0.7366 -0.64008) (xy -4.7244 -0.64008) (xy -5.2324 -0.64008) (xy -5.2324 4.54152)
				(xy -4.7244 4.54152)
			)
			(stroke
				(width 0)
				(type default)
			)
			(fill no)
			(layer "B.CrtYd")
		)
		(fp_line
			(start -5.2324 -0.64008)
			(end -5.2324 4.54152)
			(stroke
				(width 0.1)
				(type default)
			)
			(layer "B.Fab")
		)
		(fp_line
			(start -5.2324 4.54152)
			(end -0.7366 4.54152)
			(stroke
				(width 0.1)
				(type default)
			)
			(layer "B.Fab")
		)
		(fp_line
			(start -3.302 0.49022)
			(end -3.302 -0.64008)
			(stroke
				(width 0.1)
				(type default)
			)
			(layer "B.Fab")
		)
		(fp_line
			(start -2.667 -0.64008)
			(end -2.667 0.49022)
			(stroke
				(width 0.1)
				(type default)
			)
			(layer "B.Fab")
		)
		(fp_line
			(start -2.667 0.49022)
			(end -3.302 0.49022)
			(stroke
				(width 0.1)
				(type default)
			)
			(layer "B.Fab")
		)
		(fp_line
			(start -0.7366 -0.64008)
			(end -5.2324 -0.64008)
			(stroke
				(width 0.1)
				(type default)
			)
			(layer "B.Fab")
		)
		(fp_line
			(start -0.7366 4.54152)
			(end -0.7366 -0.64008)
			(stroke
				(width 0.1)
				(type default)
			)
			(layer "B.Fab")
		)
		(fp_circle
			(center 1.612138 -0.684784)
			(end 1.739138 -0.684784)
			(stroke
				(width 0.254)
				(type default)
			)
			(fill no)
			(layer "B.Fab")
		)
		(pad "1" smd rect
			(at 0 0 180)
			(size 2.159 0.381)
			(layers "B.Cu" "B.Mask" "B.Paste")
			(net "PD_GTL2104_DIR_1")
		)
		(pad "2" smd rect
			(at 0 0.65024 180)
			(size 2.159 0.381)
			(layers "B.Cu" "B.Mask" "B.Paste")
			(net "PWRGD_CPUPWRGD_GTL")
		)
		(pad "3" smd rect
			(at 0 1.30048 180)
			(size 2.159 0.381)
			(layers "B.Cu" "B.Mask" "B.Paste")
			(net "H_CPU1_FIVR_FAULT_G")
		)
		(pad "4" smd rect
			(at 0 1.95072 180)
			(size 2.159 0.381)
			(layers "B.Cu" "B.Mask" "B.Paste")
			(net "P0V7_GTL2104_VREF_1")
		)
		(pad "5" smd rect
			(at 0 2.60096 180)
			(size 2.159 0.381)
			(layers "B.Cu" "B.Mask" "B.Paste")
			(net "H_CPU_CATERR_G_N")
		)
		(pad "6" smd rect
			(at 0 3.2512 180)
			(size 2.159 0.381)
			(layers "B.Cu" "B.Mask" "B.Paste")
			(net "H_CPU1_THERMTRIP_G_N")
		)
		(pad "7" smd rect
			(at 0 3.90144 180)
			(size 2.159 0.381)
			(layers "B.Cu" "B.Mask" "B.Paste")
			(net "GND")
		)
		(pad "8" smd rect
			(at -5.969 3.90144 180)
			(size 2.159 0.381)
			(layers "B.Cu" "B.Mask" "B.Paste")
			(net "GND")
		)
		(pad "9" smd rect
			(at -5.969 3.2512 180)
			(size 2.159 0.381)
			(layers "B.Cu" "B.Mask" "B.Paste")
			(net "FM_CPU1_THERMTRIP_LVT3_R_N")
		)
		(pad "10" smd rect
			(at -5.969 2.60096 180)
			(size 2.159 0.381)
			(layers "B.Cu" "B.Mask" "B.Paste")
			(net "FM_CPU_CATERR_LVT3_R2_N")
		)
		(pad "11" smd rect
			(at -5.969 1.95072 180)
			(size 2.159 0.381)
			(layers "B.Cu" "B.Mask" "B.Paste")
			(net "GND")
		)
		(pad "12" smd rect
			(at -5.969 1.30048 180)
			(size 2.159 0.381)
			(layers "B.Cu" "B.Mask" "B.Paste")
			(net "FM_CPU1_FIVR_FAULT_R_LVT3")
		)
		(pad "13" smd rect
			(at -5.969 0.65024 180)
			(size 2.159 0.381)
			(layers "B.Cu" "B.Mask" "B.Paste")
			(net "PWRGD_CPUPWRGD_R1")
		)
		(pad "14" smd rect
			(at -5.969 0 180)
			(size 2.159 0.381)
			(layers "B.Cu" "B.Mask" "B.Paste")
			(net "P3V3")
		)
	)
)
